# BASEBOARD_FAB2 (Tioga Pass) — schematic netlist excerpt (pin names and nets, part order shuffled) for the footprints in the layout excerpt that follows; sources: Cadence DE-HDL packaged netlist, KiCad conversion of Wiwynn_Tioga_Pass_MB.brd

J9A1  CONN4_D42317002  CONN  pkg PIP  page 135
  IO1  = GND
  IO2  = PU_KEY_CONN_PIN2_R
  IO3  = GND
  IO4  = FM_PCH_SATA_RAID_KEY_R

R8B21  RES  49.9 1% EMPTY  pkg 0402  page 114 : A = H_PMSYNC_CLK_24M ; B = GND

(kicad_pcb
	(version 20260206)
	(generator "pcbnew")
	(generator_version "10.0")
	(general
		(thickness 1.6)
		(legacy_teardrops no)
	)
	(paper "A4")
	(title_block
		(title "Wiwynn_Tioga_Pass_MB.brd")
		(comment 1 "Tioga Pass / footprints 1619-1620 of 4770")
	)
	(layers
		(0 "F.Cu" signal "TOP")
		(4 "In1.Cu" signal "L2GND")
		(6 "In2.Cu" signal "L3")
		(8 "In3.Cu" signal "L4GND")
		(10 "In4.Cu" signal "L5")
		(12 "In5.Cu" signal "L6GND")
		(14 "In6.Cu" signal "L7VCC")
		(16 "In7.Cu" signal "L8VCC")
		(18 "In8.Cu" signal "L9GND")
		(20 "In9.Cu" signal "L10")
		(22 "In10.Cu" signal "L11GND")
		(24 "In11.Cu" signal "L12")
		(26 "In12.Cu" signal "L13GND")
		(2 "B.Cu" signal "BOTTOM")
		(9 "F.Adhes" user "F.Adhesive")
		(11 "B.Adhes" user "B.Adhesive")
		(13 "F.Paste" user "Package Geometry/Pastemask Top")
		(15 "B.Paste" user "Package Geometry/Pastemask Bottom")
		(5 "F.SilkS" user "Ref Des/Silkscreen Top")
		(7 "B.SilkS" user "Ref Des/Silkscreen Bottom")
		(1 "F.Mask" user "Board Geometry/Soldermask Top")
		(3 "B.Mask" user "Board Geometry/Soldermask Bottom")
		(17 "Dwgs.User" user "User.Drawings")
		(19 "Cmts.User" user "User.Comments")
		(21 "Eco1.User" user "User.Eco1")
		(23 "Eco2.User" user "User.Eco2")
		(25 "Edge.Cuts" user "Board Geometry/Outline")
		(27 "Margin" user)
		(31 "F.CrtYd" user "Package Geometry/Place Bound Top")
		(29 "B.CrtYd" user "Package Geometry/Place Bound Bottom")
		(35 "F.Fab" user "Ref Des/Assembly Top")
		(33 "B.Fab" user "Ref Des/Assembly Bottom")
	)
	(footprint ""
		(layer "F.Cu")
		(at 413.4612 -117.8814 180)
		(property "Reference" "R8B21"
			(at 0 0 180)
			(layer "F.SilkS")
			(hide yes)
			(effects
				(font
					(size 1.27 1.27)
				)
			)
		)
		(property "Value" ""
			(at 0 0 180)
			(layer "F.Fab")
			(effects
				(font
					(size 1.27 1.27)
				)
			)
		)
		(duplicate_pad_numbers_are_jumpers no)
		(fp_poly
			(pts
				(xy -0.2794 -0.1016) (xy 0.2794 -0.1016) (xy 0.2794 0.9906) (xy -0.2794 0.9906)
			)
			(stroke
				(width 0)
				(type default)
			)
			(fill no)
			(layer "F.CrtYd")
		)
		(fp_line
			(start 0.2794 0.9906)
			(end 0.2794 -0.1016)
			(stroke
				(width 0.1)
				(type default)
			)
			(layer "F.Fab")
		)
		(fp_line
			(start 0.2794 -0.1016)
			(end -0.2794 -0.1016)
			(stroke
				(width 0.1)
				(type default)
			)
			(layer "F.Fab")
		)
		(fp_line
			(start -0.2794 0.9906)
			(end 0.2794 0.9906)
			(stroke
				(width 0.1)
				(type default)
			)
			(layer "F.Fab")
		)
		(fp_line
			(start -0.2794 -0.1016)
			(end -0.2794 0.9906)
			(stroke
				(width 0.1)
				(type default)
			)
			(layer "F.Fab")
		)
		(pad "1" smd rect
			(at 0 0 180)
			(size 0.508 0.508)
			(layers "F.Cu" "F.Mask" "F.Paste")
			(net "H_PMSYNC_CLK_24M")
		)
		(pad "2" smd rect
			(at 0 0.889 180)
			(size 0.508 0.508)
			(layers "F.Cu" "F.Mask" "F.Paste")
			(net "GND")
		)
		(zone
			(layer "F.Cu")
			(hatch none 0.5)
			(connect_pads
				(clearance 0)
			)
			(min_thickness 0.25)
			(keepout
				(tracks not_allowed)
				(vias allowed)
				(pads allowed)
				(copperpour not_allowed)
				(footprints allowed)
			)
			(placement
				(enabled no)
				(sheetname "")
			)
			(fill
				(thermal_gap 0.5)
				(thermal_bridge_width 0.5)
				(island_removal_mode 0)
			)
			(polygon
				(pts
					(xy 413.7152 -118.5164) (xy 413.2072 -118.5164) (xy 413.2072 -118.1354) (xy 413.7152 -118.1354)
				)
			)
		)
		(zone
			(layer "F.Cu")
			(hatch none 0.5)
			(connect_pads
				(clearance 0)
			)
			(min_thickness 0.25)
			(keepout
				(tracks allowed)
				(vias not_allowed)
				(pads allowed)
				(copperpour not_allowed)
				(footprints allowed)
			)
			(placement
				(enabled no)
				(sheetname "")
			)
			(fill
				(thermal_gap 0.5)
				(thermal_bridge_width 0.5)
				(island_removal_mode 0)
			)
			(polygon
				(pts
					(xy 413.7152 -118.1354) (xy 413.2072 -118.1354) (xy 413.2072 -118.5164) (xy 413.7152 -118.5164)
				)
			)
		)
	)
	(footprint ""
		(layer "F.Cu")
		(at 470.2175 -142.494 180)
		(property "Reference" "J9A1"
			(at -2.29362 -1.86055 0)
			(unlocked yes)
			(layer "B.SilkS")
			(effects
				(font
					(size 0.7874 0.5842)
					(thickness 0.1524)
				)
				(justify left mirror)
			)
		)
		(property "Value" ""
			(at 0 0 180)
			(layer "F.Fab")
			(effects
				(font
					(size 1.27 1.27)
				)
			)
		)
		(duplicate_pad_numbers_are_jumpers no)
		(fp_line
			(start 2.153412 8.64997)
			(end -1.746504 8.64997)
			(stroke
				(width 0.1524)
				(type default)
			)
			(layer "F.SilkS")
		)
		(fp_line
			(start 2.153412 -2.649982)
			(end 2.153412 8.64997)
			(stroke
				(width 0.1524)
				(type default)
			)
			(layer "F.SilkS")
		)
		(fp_line
			(start -1.746504 8.64997)
			(end -1.746504 -2.649982)
			(stroke
				(width 0.1524)
				(type default)
			)
			(layer "F.SilkS")
		)
		(fp_line
			(start -1.746504 -2.649982)
			(end 2.153412 -2.649982)
			(stroke
				(width 0.1524)
				(type default)
			)
			(layer "F.SilkS")
		)
		(fp_poly
			(pts
				(xy -3.664204 -0.499618) (xy -3.664204 0.516382) (xy -2.394204 0.008382)
			)
			(stroke
				(width 0)
				(type default)
			)
			(fill yes)
			(layer "F.SilkS")
		)
		(fp_poly
			(pts
				(xy 1.950974 0.512064) (xy 1.950974 -0.503936) (xy 0.680974 0.004064)
			)
			(stroke
				(width 0)
				(type default)
			)
			(fill yes)
			(layer "B.SilkS")
		)
		(fp_poly
			(pts
				(xy -1.746504 -2.649982) (xy -1.746504 8.64997) (xy 2.153412 8.64997) (xy 2.153412 -2.649982)
			)
			(stroke
				(width 0)
				(type default)
			)
			(fill no)
			(layer "F.CrtYd")
		)
		(fp_poly
			(pts
				(xy -3.664204 -0.499618) (xy -3.664204 0.516382) (xy -2.394204 0.008382)
			)
			(stroke
				(width 0)
				(type default)
			)
			(fill yes)
			(layer "B.Fab")
		)
		(fp_line
			(start 2.153412 8.64997)
			(end -1.746504 8.64997)
			(stroke
				(width 0.1)
				(type default)
			)
			(layer "F.Fab")
		)
		(fp_line
			(start 2.153412 -2.649982)
			(end 2.153412 8.64997)
			(stroke
				(width 0.1)
				(type default)
			)
			(layer "F.Fab")
		)
		(fp_line
			(start -1.746504 8.64997)
			(end -1.746504 -2.649982)
			(stroke
				(width 0.1)
				(type default)
			)
			(layer "F.Fab")
		)
		(fp_line
			(start -1.746504 -2.649982)
			(end 2.153412 -2.649982)
			(stroke
				(width 0.1)
				(type default)
			)
			(layer "F.Fab")
		)
		(fp_poly
			(pts
				(xy -3.664204 -0.499618) (xy -3.664204 0.516382) (xy -2.394204 0.008382)
			)
			(stroke
				(width 0)
				(type default)
			)
			(fill yes)
			(layer "F.Fab")
		)
		(fp_text user "4"
			(at 0.7493 9.21893 0)
			(unlocked yes)
			(layer "F.SilkS")
			(effects
				(font
					(size 0.7874 0.5842)
					(thickness 0.1524)
				)
				(justify left)
			)
		)
		(fp_text user "4"
			(at -2.218436 6.033516 180)
			(unlocked yes)
			(layer "B.SilkS")
			(effects
				(font
					(size 0.7874 0.5842)
					(thickness 0.1524)
				)
				(justify left mirror)
			)
		)
		(fp_text user "4"
			(at -2.218436 6.033516 180)
			(unlocked yes)
			(layer "B.Fab")
			(effects
				(font
					(size 0.7874 0.5842)
					(thickness 0.1524)
				)
				(justify left mirror)
			)
		)
		(fp_text user "4"
			(at 2.962402 8.50265 0)
			(unlocked yes)
			(layer "F.Fab")
			(effects
				(font
					(size 0.7874 0.5842)
					(thickness 0.1524)
				)
				(justify left)
			)
		)
		(pad "1" thru_hole rect
			(at 0 0 180)
			(size 1.1938 1.1938)
			(drill 0.8128)
			(layers "*.Cu" "*.Mask")
			(remove_unused_layers no)
			(net "GND")
			(clearance 0.127)
			(thermal_gap 0.127)
			(padstack
				(mode front_inner_back)
				(layer "Inner"
					(shape circle)
					(size 1.1938 1.1938)
					(clearance 0.127)
				)
				(layer "B.Cu"
					(shape rect)
					(size 1.1938 1.1938)
					(clearance 0.127)
				)
			)
		)
		(pad "2" thru_hole circle
			(at 0 1.999996 180)
			(size 1.1938 1.1938)
			(drill 0.8128)
			(layers "*.Cu" "*.Mask")
			(remove_unused_layers no)
			(net "PU_KEY_CONN_PIN2_R")
			(clearance 0.127)
			(thermal_gap 0.127)
		)
		(pad "3" thru_hole circle
			(at 0 3.999992 180)
			(size 1.1938 1.1938)
			(drill 0.8128)
			(layers "*.Cu" "*.Mask")
			(remove_unused_layers no)
			(net "GND")
			(clearance 0.127)
			(thermal_gap 0.127)
		)
		(pad "4" thru_hole circle
			(at 0 5.999988 180)
			(size 1.1938 1.1938)
			(drill 0.8128)
			(layers "*.Cu" "*.Mask")
			(remove_unused_layers no)
			(net "FM_PCH_SATA_RAID_KEY_R")
			(clearance 0.127)
			(thermal_gap 0.127)
		)
	)
)
